(kicad_pcb
	(version 20260206)
	(generator "pcbnew")
	(generator_version "10.0")
	(general
		(thickness 1.6)
		(legacy_teardrops no)
	)
	(paper "A4")
	(title_block
		(title "03242023_DA0F0TMBIJ0_F0T_Motherboard_J_brd_V01_OCP.brd")
		(comment 1 "Grand Teton / footprints 5323-5328 of 6105")
	)
	(layers
		(0 "F.Cu" signal "TOP")
		(4 "In1.Cu" signal "GND")
		(6 "In2.Cu" signal "IN1")
		(8 "In3.Cu" signal "GND1")
		(10 "In4.Cu" signal "IN2")
		(12 "In5.Cu" signal "GND2")
		(14 "In6.Cu" signal "IN3")
		(16 "In7.Cu" signal "GND3")
		(18 "In8.Cu" signal "VCC")
		(20 "In9.Cu" signal "VCC1")
		(22 "In10.Cu" signal "GND4")
		(24 "In11.Cu" signal "IN4")
		(26 "In12.Cu" signal "GND5")
		(28 "In13.Cu" signal "IN5")
		(30 "In14.Cu" signal "GND6")
		(32 "In15.Cu" signal "IN6")
		(34 "In16.Cu" signal "GND7")
		(2 "B.Cu" signal "BOTTOM")
		(9 "F.Adhes" user "F.Adhesive")
		(11 "B.Adhes" user "B.Adhesive")
		(13 "F.Paste" user "Package Geometry/Pastemask Top")
		(15 "B.Paste" user "Package Geometry/Pastemask Bottom")
		(5 "F.SilkS" user "Ref Des/Silkscreen Top")
		(7 "B.SilkS" user "Ref Des/Silkscreen Bottom")
		(1 "F.Mask" user "Board Geometry/Soldermask Top")
		(3 "B.Mask" user "Board Geometry/Soldermask Bottom")
		(17 "Dwgs.User" user "User.Drawings")
		(19 "Cmts.User" user "User.Comments")
		(21 "Eco1.User" user "User.Eco1")
		(23 "Eco2.User" user "User.Eco2")
		(25 "Edge.Cuts" user "Board Geometry/Outline")
		(27 "Margin" user)
		(31 "F.CrtYd" user "Package Geometry/Place Bound Top")
		(29 "B.CrtYd" user "Package Geometry/Place Bound Bottom")
		(35 "F.Fab" user "Ref Des/Assembly Top")
		(33 "B.Fab" user "Ref Des/Assembly Bottom")
	)
	(footprint ""
		(layer "B.Cu")
		(at 446.55105 -10.594086 -90)
		(property "Reference" "R409"
			(at 0 0 90)
			(layer "B.SilkS")
			(hide yes)
			(effects
				(font
					(size 1.27 1.27)
				)
				(justify mirror)
			)
		)
		(property "Value" ""
			(at 0 0 90)
			(layer "B.Fab")
			(effects
				(font
					(size 1.27 1.27)
				)
				(justify mirror)
			)
		)
		(duplicate_pad_numbers_are_jumpers no)
		(fp_line
			(start -0.7874 0.4064)
			(end 0.7874 0.4064)
			(stroke
				(width 0.1524)
				(type default)
			)
			(layer "B.SilkS")
		)
		(fp_line
			(start 0.7874 0.4064)
			(end 0.7874 -0.4064)
			(stroke
				(width 0.1524)
				(type default)
			)
			(layer "B.SilkS")
		)
		(fp_line
			(start -0.7874 -0.4064)
			(end -0.7874 0.4064)
			(stroke
				(width 0.1524)
				(type default)
			)
			(layer "B.SilkS")
		)
		(fp_line
			(start 0.7874 -0.4064)
			(end -0.7874 -0.4064)
			(stroke
				(width 0.1524)
				(type default)
			)
			(layer "B.SilkS")
		)
		(fp_line
			(start -0.67945 0.3048)
			(end -0.120396 0.3048)
			(stroke
				(width 0.1)
				(type default)
			)
			(layer "B.Fab")
		)
		(fp_line
			(start -0.120396 0.3048)
			(end -0.120396 0.2794)
			(stroke
				(width 0.1)
				(type default)
			)
			(layer "B.Fab")
		)
		(fp_line
			(start 0.12065 0.3048)
			(end 0.67945 0.3048)
			(stroke
				(width 0.1)
				(type default)
			)
			(layer "B.Fab")
		)
		(fp_line
			(start 0.67945 0.3048)
			(end 0.67945 -0.305054)
			(stroke
				(width 0.1)
				(type default)
			)
			(layer "B.Fab")
		)
		(fp_line
			(start -0.120396 0.2794)
			(end 0.12065 0.2794)
			(stroke
				(width 0.1)
				(type default)
			)
			(layer "B.Fab")
		)
		(fp_line
			(start 0.12065 0.2794)
			(end 0.12065 0.3048)
			(stroke
				(width 0.1)
				(type default)
			)
			(layer "B.Fab")
		)
		(fp_line
			(start -0.12065 -0.2794)
			(end -0.12065 -0.3048)
			(stroke
				(width 0.1)
				(type default)
			)
			(layer "B.Fab")
		)
		(fp_line
			(start 0.12065 -0.2794)
			(end -0.12065 -0.2794)
			(stroke
				(width 0.1)
				(type default)
			)
			(layer "B.Fab")
		)
		(fp_line
			(start -0.67945 -0.3048)
			(end -0.67945 0.3048)
			(stroke
				(width 0.1)
				(type default)
			)
			(layer "B.Fab")
		)
		(fp_line
			(start -0.12065 -0.3048)
			(end -0.67945 -0.3048)
			(stroke
				(width 0.1)
				(type default)
			)
			(layer "B.Fab")
		)
		(fp_line
			(start 0.12065 -0.305054)
			(end 0.12065 -0.2794)
			(stroke
				(width 0.1)
				(type default)
			)
			(layer "B.Fab")
		)
		(fp_line
			(start 0.67945 -0.305054)
			(end 0.12065 -0.305054)
			(stroke
				(width 0.1)
				(type default)
			)
			(layer "B.Fab")
		)
		(pad "1" smd circle
			(at 0.40005 0 90)
			(size 0 0)
			(layers "B.Cu" "B.Mask" "B.Paste")
			(net "P3V3_OCP_SFF")
		)
		(pad "2" smd circle
			(at -0.40005 0 90)
			(size 0 0)
			(layers "B.Cu" "B.Mask" "B.Paste")
			(net "OCP_SFF_ID0")
		)
	)
	(footprint ""
		(layer "B.Cu")
		(at 444.42126 -316.709044 90)
		(property "Reference" "R3887"
			(at 0 0 90)
			(layer "B.SilkS")
			(hide yes)
			(effects
				(font
					(size 1.27 1.27)
				)
				(justify mirror)
			)
		)
		(property "Value" ""
			(at 0 0 90)
			(layer "B.Fab")
			(effects
				(font
					(size 1.27 1.27)
				)
				(justify mirror)
			)
		)
		(duplicate_pad_numbers_are_jumpers no)
		(fp_line
			(start 0.7874 -0.4064)
			(end -0.7874 -0.4064)
			(stroke
				(width 0.1524)
				(type default)
			)
			(layer "B.SilkS")
		)
		(fp_line
			(start -0.7874 -0.4064)
			(end -0.7874 0.4064)
			(stroke
				(width 0.1524)
				(type default)
			)
			(layer "B.SilkS")
		)
		(fp_line
			(start 0.7874 0.4064)
			(end 0.7874 -0.4064)
			(stroke
				(width 0.1524)
				(type default)
			)
			(layer "B.SilkS")
		)
		(fp_line
			(start -0.7874 0.4064)
			(end 0.7874 0.4064)
			(stroke
				(width 0.1524)
				(type default)
			)
			(layer "B.SilkS")
		)
		(fp_line
			(start 0.67945 -0.305054)
			(end 0.12065 -0.305054)
			(stroke
				(width 0.1)
				(type default)
			)
			(layer "B.Fab")
		)
		(fp_line
			(start 0.12065 -0.305054)
			(end 0.12065 -0.2794)
			(stroke
				(width 0.1)
				(type default)
			)
			(layer "B.Fab")
		)
		(fp_line
			(start -0.12065 -0.3048)
			(end -0.67945 -0.3048)
			(stroke
				(width 0.1)
				(type default)
			)
			(layer "B.Fab")
		)
		(fp_line
			(start -0.67945 -0.3048)
			(end -0.67945 0.3048)
			(stroke
				(width 0.1)
				(type default)
			)
			(layer "B.Fab")
		)
		(fp_line
			(start 0.12065 -0.2794)
			(end -0.12065 -0.2794)
			(stroke
				(width 0.1)
				(type default)
			)
			(layer "B.Fab")
		)
		(fp_line
			(start -0.12065 -0.2794)
			(end -0.12065 -0.3048)
			(stroke
				(width 0.1)
				(type default)
			)
			(layer "B.Fab")
		)
		(fp_line
			(start 0.12065 0.2794)
			(end 0.12065 0.3048)
			(stroke
				(width 0.1)
				(type default)
			)
			(layer "B.Fab")
		)
		(fp_line
			(start -0.120396 0.2794)
			(end 0.12065 0.2794)
			(stroke
				(width 0.1)
				(type default)
			)
			(layer "B.Fab")
		)
		(fp_line
			(start 0.67945 0.3048)
			(end 0.67945 -0.305054)
			(stroke
				(width 0.1)
				(type default)
			)
			(layer "B.Fab")
		)
		(fp_line
			(start 0.12065 0.3048)
			(end 0.67945 0.3048)
			(stroke
				(width 0.1)
				(type default)
			)
			(layer "B.Fab")
		)
		(fp_line
			(start -0.120396 0.3048)
			(end -0.120396 0.2794)
			(stroke
				(width 0.1)
				(type default)
			)
			(layer "B.Fab")
		)
		(fp_line
			(start -0.67945 0.3048)
			(end -0.120396 0.3048)
			(stroke
				(width 0.1)
				(type default)
			)
			(layer "B.Fab")
		)
		(pad "1" smd circle
			(at 0.40005 0 270)
			(size 0 0)
			(layers "B.Cu" "B.Mask" "B.Paste")
			(net "I3C_SPD_DDREFGH_CPU0_LVC1_SCL_4")
		)
		(pad "2" smd circle
			(at -0.40005 0 270)
			(size 0 0)
			(layers "B.Cu" "B.Mask" "B.Paste")
			(net "I3C_SPD_DDREFGH_CPU0_LVC1_SCL")
		)
	)
	(footprint ""
		(layer "B.Cu")
		(at 45.872146 -319.268856 180)
		(property "Reference" "C59"
			(at 0 0 0)
			(layer "B.SilkS")
			(hide yes)
			(effects
				(font
					(size 1.27 1.27)
				)
				(justify mirror)
			)
		)
		(property "Value" ""
			(at 0 0 0)
			(layer "B.Fab")
			(effects
				(font
					(size 1.27 1.27)
				)
				(justify mirror)
			)
		)
		(duplicate_pad_numbers_are_jumpers no)
		(fp_line
			(start 0.7874 0.4064)
			(end 0.7874 -0.4064)
			(stroke
				(width 0.1524)
				(type default)
			)
			(layer "B.SilkS")
		)
		(fp_line
			(start 0.7874 -0.4064)
			(end -0.7874 -0.4064)
			(stroke
				(width 0.1524)
				(type default)
			)
			(layer "B.SilkS")
		)
		(fp_line
			(start -0.7874 0.4064)
			(end 0.7874 0.4064)
			(stroke
				(width 0.1524)
				(type default)
			)
			(layer "B.SilkS")
		)
		(fp_line
			(start -0.7874 -0.4064)
			(end -0.7874 0.4064)
			(stroke
				(width 0.1524)
				(type default)
			)
			(layer "B.SilkS")
		)
		(fp_line
			(start 0.67945 0.3048)
			(end 0.67945 -0.305054)
			(stroke
				(width 0.1)
				(type default)
			)
			(layer "B.Fab")
		)
		(fp_line
			(start 0.67945 -0.305054)
			(end 0.12065 -0.305054)
			(stroke
				(width 0.1)
				(type default)
			)
			(layer "B.Fab")
		)
		(fp_line
			(start 0.12065 0.3048)
			(end 0.67945 0.3048)
			(stroke
				(width 0.1)
				(type default)
			)
			(layer "B.Fab")
		)
		(fp_line
			(start 0.12065 0.2794)
			(end 0.12065 0.3048)
			(stroke
				(width 0.1)
				(type default)
			)
			(layer "B.Fab")
		)
		(fp_line
			(start 0.12065 -0.2794)
			(end -0.12065 -0.2794)
			(stroke
				(width 0.1)
				(type default)
			)
			(layer "B.Fab")
		)
		(fp_line
			(start 0.12065 -0.305054)
			(end 0.12065 -0.2794)
			(stroke
				(width 0.1)
				(type default)
			)
			(layer "B.Fab")
		)
		(fp_line
			(start -0.120396 0.3048)
			(end -0.120396 0.2794)
			(stroke
				(width 0.1)
				(type default)
			)
			(layer "B.Fab")
		)
		(fp_line
			(start -0.120396 0.2794)
			(end 0.12065 0.2794)
			(stroke
				(width 0.1)
				(type default)
			)
			(layer "B.Fab")
		)
		(fp_line
			(start -0.12065 -0.2794)
			(end -0.12065 -0.3048)
			(stroke
				(width 0.1)
				(type default)
			)
			(layer "B.Fab")
		)
		(fp_line
			(start -0.12065 -0.3048)
			(end -0.67945 -0.3048)
			(stroke
				(width 0.1)
				(type default)
			)
			(layer "B.Fab")
		)
		(fp_line
			(start -0.67945 0.3048)
			(end -0.120396 0.3048)
			(stroke
				(width 0.1)
				(type default)
			)
			(layer "B.Fab")
		)
		(fp_line
			(start -0.67945 -0.3048)
			(end -0.67945 0.3048)
			(stroke
				(width 0.1)
				(type default)
			)
			(layer "B.Fab")
		)
		(pad "1" smd circle
			(at 0.40005 0)
			(size 0 0)
			(layers "B.Cu" "B.Mask" "B.Paste")
			(net "P3V3_AUX")
		)
		(pad "2" smd circle
			(at -0.40005 0)
			(size 0 0)
			(layers "B.Cu" "B.Mask" "B.Paste")
			(net "GND")
		)
	)
	(footprint ""
		(layer "B.Cu")
		(at 24.327866 -193.152776 -90)
		(property "Reference" "R701"
			(at 0 0 90)
			(layer "B.SilkS")
			(hide yes)
			(effects
				(font
					(size 1.27 1.27)
				)
				(justify mirror)
			)
		)
		(property "Value" ""
			(at 0 0 90)
			(layer "B.Fab")
			(effects
				(font
					(size 1.27 1.27)
				)
				(justify mirror)
			)
		)
		(duplicate_pad_numbers_are_jumpers no)
		(fp_line
			(start -0.7874 0.4064)
			(end 0.7874 0.4064)
			(stroke
				(width 0.1524)
				(type default)
			)
			(layer "B.SilkS")
		)
		(fp_line
			(start 0.7874 0.4064)
			(end 0.7874 -0.4064)
			(stroke
				(width 0.1524)
				(type default)
			)
			(layer "B.SilkS")
		)
		(fp_line
			(start -0.7874 -0.4064)
			(end -0.7874 0.4064)
			(stroke
				(width 0.1524)
				(type default)
			)
			(layer "B.SilkS")
		)
		(fp_line
			(start 0.7874 -0.4064)
			(end -0.7874 -0.4064)
			(stroke
				(width 0.1524)
				(type default)
			)
			(layer "B.SilkS")
		)
		(fp_line
			(start -0.67945 0.3048)
			(end -0.120396 0.3048)
			(stroke
				(width 0.1)
				(type default)
			)
			(layer "B.Fab")
		)
		(fp_line
			(start -0.120396 0.3048)
			(end -0.120396 0.2794)
			(stroke
				(width 0.1)
				(type default)
			)
			(layer "B.Fab")
		)
		(fp_line
			(start 0.12065 0.3048)
			(end 0.67945 0.3048)
			(stroke
				(width 0.1)
				(type default)
			)
			(layer "B.Fab")
		)
		(fp_line
			(start 0.67945 0.3048)
			(end 0.67945 -0.305054)
			(stroke
				(width 0.1)
				(type default)
			)
			(layer "B.Fab")
		)
		(fp_line
			(start -0.120396 0.2794)
			(end 0.12065 0.2794)
			(stroke
				(width 0.1)
				(type default)
			)
			(layer "B.Fab")
		)
		(fp_line
			(start 0.12065 0.2794)
			(end 0.12065 0.3048)
			(stroke
				(width 0.1)
				(type default)
			)
			(layer "B.Fab")
		)
		(fp_line
			(start -0.12065 -0.2794)
			(end -0.12065 -0.3048)
			(stroke
				(width 0.1)
				(type default)
			)
			(layer "B.Fab")
		)
		(fp_line
			(start 0.12065 -0.2794)
			(end -0.12065 -0.2794)
			(stroke
				(width 0.1)
				(type default)
			)
			(layer "B.Fab")
		)
		(fp_line
			(start -0.67945 -0.3048)
			(end -0.67945 0.3048)
			(stroke
				(width 0.1)
				(type default)
			)
			(layer "B.Fab")
		)
		(fp_line
			(start -0.12065 -0.3048)
			(end -0.67945 -0.3048)
			(stroke
				(width 0.1)
				(type default)
			)
			(layer "B.Fab")
		)
		(fp_line
			(start 0.12065 -0.305054)
			(end 0.12065 -0.2794)
			(stroke
				(width 0.1)
				(type default)
			)
			(layer "B.Fab")
		)
		(fp_line
			(start 0.67945 -0.305054)
			(end 0.12065 -0.305054)
			(stroke
				(width 0.1)
				(type default)
			)
			(layer "B.Fab")
		)
		(pad "1" smd circle
			(at 0.40005 0 90)
			(size 0 0)
			(layers "B.Cu" "B.Mask" "B.Paste")
			(net "RST_PLD_CPU1_DRAM_CD_N")
		)
		(pad "2" smd circle
			(at -0.40005 0 90)
			(size 0 0)
			(layers "B.Cu" "B.Mask" "B.Paste")
			(net "GND")
		)
	)
	(footprint ""
		(layer "B.Cu")
		(at 422.218104 -137.658094 -90)
		(property "Reference" "PR436"
			(at 0 0 90)
			(layer "B.SilkS")
			(hide yes)
			(effects
				(font
					(size 1.27 1.27)
				)
				(justify mirror)
			)
		)
		(property "Value" ""
			(at 0 0 90)
			(layer "B.Fab")
			(effects
				(font
					(size 1.27 1.27)
				)
				(justify mirror)
			)
		)
		(duplicate_pad_numbers_are_jumpers no)
		(fp_line
			(start -0.7874 0.4064)
			(end 0.7874 0.4064)
			(stroke
				(width 0.1524)
				(type default)
			)
			(layer "B.SilkS")
		)
		(fp_line
			(start 0.7874 0.4064)
			(end 0.7874 -0.4064)
			(stroke
				(width 0.1524)
				(type default)
			)
			(layer "B.SilkS")
		)
		(fp_line
			(start -0.7874 -0.4064)
			(end -0.7874 0.4064)
			(stroke
				(width 0.1524)
				(type default)
			)
			(layer "B.SilkS")
		)
		(fp_line
			(start 0.7874 -0.4064)
			(end -0.7874 -0.4064)
			(stroke
				(width 0.1524)
				(type default)
			)
			(layer "B.SilkS")
		)
		(fp_line
			(start -0.67945 0.3048)
			(end -0.120396 0.3048)
			(stroke
				(width 0.1)
				(type default)
			)
			(layer "B.Fab")
		)
		(fp_line
			(start -0.120396 0.3048)
			(end -0.120396 0.2794)
			(stroke
				(width 0.1)
				(type default)
			)
			(layer "B.Fab")
		)
		(fp_line
			(start 0.12065 0.3048)
			(end 0.67945 0.3048)
			(stroke
				(width 0.1)
				(type default)
			)
			(layer "B.Fab")
		)
		(fp_line
			(start 0.67945 0.3048)
			(end 0.67945 -0.305054)
			(stroke
				(width 0.1)
				(type default)
			)
			(layer "B.Fab")
		)
		(fp_line
			(start -0.120396 0.2794)
			(end 0.12065 0.2794)
			(stroke
				(width 0.1)
				(type default)
			)
			(layer "B.Fab")
		)
		(fp_line
			(start 0.12065 0.2794)
			(end 0.12065 0.3048)
			(stroke
				(width 0.1)
				(type default)
			)
			(layer "B.Fab")
		)
		(fp_line
			(start -0.12065 -0.2794)
			(end -0.12065 -0.3048)
			(stroke
				(width 0.1)
				(type default)
			)
			(layer "B.Fab")
		)
		(fp_line
			(start 0.12065 -0.2794)
			(end -0.12065 -0.2794)
			(stroke
				(width 0.1)
				(type default)
			)
			(layer "B.Fab")
		)
		(fp_line
			(start -0.67945 -0.3048)
			(end -0.67945 0.3048)
			(stroke
				(width 0.1)
				(type default)
			)
			(layer "B.Fab")
		)
		(fp_line
			(start -0.12065 -0.3048)
			(end -0.67945 -0.3048)
			(stroke
				(width 0.1)
				(type default)
			)
			(layer "B.Fab")
		)
		(fp_line
			(start 0.12065 -0.305054)
			(end 0.12065 -0.2794)
			(stroke
				(width 0.1)
				(type default)
			)
			(layer "B.Fab")
		)
		(fp_line
			(start 0.67945 -0.305054)
			(end 0.12065 -0.305054)
			(stroke
				(width 0.1)
				(type default)
			)
			(layer "B.Fab")
		)
		(pad "1" smd circle
			(at 0.40005 0 90)
			(size 0 0)
			(layers "B.Cu" "B.Mask" "B.Paste")
			(net "PVCCFA_EHV_CPU0_BTSEN")
		)
		(pad "2" smd circle
			(at -0.40005 0 90)
			(size 0 0)
			(layers "B.Cu" "B.Mask" "B.Paste")
			(net "GND")
		)
	)
	(footprint ""
		(layer "B.Cu")
		(at 41.830244 -99.75723 -90)
		(property "Reference" "R3939"
			(at 0 0 90)
			(layer "B.SilkS")
			(hide yes)
			(effects
				(font
					(size 1.27 1.27)
				)
				(justify mirror)
			)
		)
		(property "Value" ""
			(at 0 0 90)
			(layer "B.Fab")
			(effects
				(font
					(size 1.27 1.27)
				)
				(justify mirror)
			)
		)
		(duplicate_pad_numbers_are_jumpers no)
		(fp_line
			(start -0.7874 0.4064)
			(end 0.7874 0.4064)
			(stroke
				(width 0.1524)
				(type default)
			)
			(layer "B.SilkS")
		)
		(fp_line
			(start 0.7874 0.4064)
			(end 0.7874 -0.4064)
			(stroke
				(width 0.1524)
				(type default)
			)
			(layer "B.SilkS")
		)
		(fp_line
			(start -0.7874 -0.4064)
			(end -0.7874 0.4064)
			(stroke
				(width 0.1524)
				(type default)
			)
			(layer "B.SilkS")
		)
		(fp_line
			(start 0.7874 -0.4064)
			(end -0.7874 -0.4064)
			(stroke
				(width 0.1524)
				(type default)
			)
			(layer "B.SilkS")
		)
		(fp_line
			(start -0.67945 0.3048)
			(end -0.120396 0.3048)
			(stroke
				(width 0.1)
				(type default)
			)
			(layer "B.Fab")
		)
		(fp_line
			(start -0.120396 0.3048)
			(end -0.120396 0.2794)
			(stroke
				(width 0.1)
				(type default)
			)
			(layer "B.Fab")
		)
		(fp_line
			(start 0.12065 0.3048)
			(end 0.67945 0.3048)
			(stroke
				(width 0.1)
				(type default)
			)
			(layer "B.Fab")
		)
		(fp_line
			(start 0.67945 0.3048)
			(end 0.67945 -0.305054)
			(stroke
				(width 0.1)
				(type default)
			)
			(layer "B.Fab")
		)
		(fp_line
			(start -0.120396 0.2794)
			(end 0.12065 0.2794)
			(stroke
				(width 0.1)
				(type default)
			)
			(layer "B.Fab")
		)
		(fp_line
			(start 0.12065 0.2794)
			(end 0.12065 0.3048)
			(stroke
				(width 0.1)
				(type default)
			)
			(layer "B.Fab")
		)
		(fp_line
			(start -0.12065 -0.2794)
			(end -0.12065 -0.3048)
			(stroke
				(width 0.1)
				(type default)
			)
			(layer "B.Fab")
		)
		(fp_line
			(start 0.12065 -0.2794)
			(end -0.12065 -0.2794)
			(stroke
				(width 0.1)
				(type default)
			)
			(layer "B.Fab")
		)
		(fp_line
			(start -0.67945 -0.3048)
			(end -0.67945 0.3048)
			(stroke
				(width 0.1)
				(type default)
			)
			(layer "B.Fab")
		)
		(fp_line
			(start -0.12065 -0.3048)
			(end -0.67945 -0.3048)
			(stroke
				(width 0.1)
				(type default)
			)
			(layer "B.Fab")
		)
		(fp_line
			(start 0.12065 -0.305054)
			(end 0.12065 -0.2794)
			(stroke
				(width 0.1)
				(type default)
			)
			(layer "B.Fab")
		)
		(fp_line
			(start 0.67945 -0.305054)
			(end 0.12065 -0.305054)
			(stroke
				(width 0.1)
				(type default)
			)
			(layer "B.Fab")
		)
		(pad "1" smd rect
			(at 0.40005 0 270)
			(size 0.4572 0.508)
			(layers "B.Cu" "B.Mask" "B.Paste")
			(net "P12V_E1S_0_ISENSE_MAM_MAM")
		)
		(pad "2" smd rect
			(at -0.40005 0 270)
			(size 0.4572 0.508)
			(layers "B.Cu" "B.Mask" "B.Paste")
			(net "P12V_E1S_0_ISENSE_MAM")
		)
	)
)
